(kicad_pcb
	(version 20260206)
	(generator "pcbnew")
	(generator_version "10.0")
	(general
		(thickness 1.6)
		(legacy_teardrops no)
	)
	(paper "A4")
	(title_block
		(title "01162023_DA0F0TEBIF0_F0T_Expander_BD_F_brd_V02_OCP.brd")
		(comment 1 "Grand Teton / footprints 3697-3703 of 9728")
	)
	(layers
		(0 "F.Cu" signal "TOP")
		(4 "In1.Cu" signal "GND")
		(6 "In2.Cu" signal "VCC")
		(8 "In3.Cu" signal "VCC1")
		(10 "In4.Cu" signal "GND1")
		(12 "In5.Cu" signal "IN1")
		(14 "In6.Cu" signal "GND2")
		(16 "In7.Cu" signal "IN2")
		(18 "In8.Cu" signal "GND3")
		(20 "In9.Cu" signal "IN3")
		(22 "In10.Cu" signal "GND4")
		(24 "In11.Cu" signal "IN4")
		(26 "In12.Cu" signal "GND5")
		(28 "In13.Cu" signal "IN5")
		(30 "In14.Cu" signal "GND6")
		(32 "In15.Cu" signal "IN6")
		(34 "In16.Cu" signal "GND7")
		(2 "B.Cu" signal "BOTTOM")
		(9 "F.Adhes" user "F.Adhesive")
		(11 "B.Adhes" user "B.Adhesive")
		(13 "F.Paste" user "Package Geometry/Pastemask Top")
		(15 "B.Paste" user "Package Geometry/Pastemask Bottom")
		(5 "F.SilkS" user "Ref Des/Silkscreen Top")
		(7 "B.SilkS" user "Ref Des/Silkscreen Bottom")
		(1 "F.Mask" user "Board Geometry/Soldermask Top")
		(3 "B.Mask" user "Board Geometry/Soldermask Bottom")
		(17 "Dwgs.User" user "User.Drawings")
		(19 "Cmts.User" user "User.Comments")
		(21 "Eco1.User" user "User.Eco1")
		(23 "Eco2.User" user "User.Eco2")
		(25 "Edge.Cuts" user "Board Geometry/Outline")
		(27 "Margin" user)
		(31 "F.CrtYd" user "Package Geometry/Place Bound Top")
		(29 "B.CrtYd" user "Package Geometry/Place Bound Bottom")
		(35 "F.Fab" user "Ref Des/Assembly Top")
		(33 "B.Fab" user "Ref Des/Assembly Bottom")
	)
	(footprint ""
		(layer "F.Cu")
		(at 152.738328 -131.323334)
		(property "Reference" "C251"
			(at 0 0 0)
			(layer "F.SilkS")
			(hide yes)
			(effects
				(font
					(size 1.27 1.27)
				)
			)
		)
		(property "Value" ""
			(at 0 0 0)
			(layer "F.Fab")
			(effects
				(font
					(size 1.27 1.27)
				)
			)
		)
		(duplicate_pad_numbers_are_jumpers no)
		(fp_line
			(start -0.299974 -0.150114)
			(end 0.299974 -0.150114)
			(stroke
				(width 0.1)
				(type default)
			)
			(layer "F.Fab")
		)
		(fp_line
			(start -0.299974 0.150114)
			(end -0.299974 -0.150114)
			(stroke
				(width 0.1)
				(type default)
			)
			(layer "F.Fab")
		)
		(fp_line
			(start 0.299974 -0.150114)
			(end 0.299974 0.150114)
			(stroke
				(width 0.1)
				(type default)
			)
			(layer "F.Fab")
		)
		(fp_line
			(start 0.299974 0.150114)
			(end -0.299974 0.150114)
			(stroke
				(width 0.1)
				(type default)
			)
			(layer "F.Fab")
		)
		(pad "1" smd rect
			(at -0.2667 0)
			(size 0.3048 0.381)
			(layers "F.Cu" "F.Mask" "F.Paste")
			(net "P5E_PEX1_STN1_TX_DN<28>")
		)
		(pad "2" smd rect
			(at 0.2667 0)
			(size 0.3048 0.381)
			(layers "F.Cu" "F.Mask" "F.Paste")
			(net "P5E_PEX1_STN1_TX_C_DN<28>")
		)
	)
	(footprint ""
		(layer "F.Cu")
		(at 361.521756 -129.799334 180)
		(property "Reference" "PD9"
			(at 4.346956 2.584196 0)
			(unlocked yes)
			(layer "F.SilkS")
			(effects
				(font
					(size 0.7874 0.5842)
					(thickness 0.1524)
				)
				(justify left)
			)
		)
		(property "Value" ""
			(at 0 0 180)
			(layer "F.Fab")
			(effects
				(font
					(size 1.27 1.27)
				)
			)
		)
		(duplicate_pad_numbers_are_jumpers no)
		(fp_line
			(start 4.240784 1.970024)
			(end 4.240784 -1.970024)
			(stroke
				(width 0.1524)
				(type default)
			)
			(layer "F.SilkS")
		)
		(fp_line
			(start 4.240784 -1.970024)
			(end -3.656584 -1.970024)
			(stroke
				(width 0.1524)
				(type default)
			)
			(layer "F.SilkS")
		)
		(fp_line
			(start -3.656584 1.970024)
			(end 4.240784 1.970024)
			(stroke
				(width 0.1524)
				(type default)
			)
			(layer "F.SilkS")
		)
		(fp_line
			(start -3.656584 -1.970024)
			(end -3.656584 1.970024)
			(stroke
				(width 0.1524)
				(type default)
			)
			(layer "F.SilkS")
		)
		(fp_poly
			(pts
				(xy 3.580384 1.970024) (xy 3.580384 -1.970024) (xy 4.240784 -1.970024) (xy 4.240784 1.970024)
			)
			(stroke
				(width 0)
				(type default)
			)
			(fill yes)
			(layer "F.SilkS")
		)
		(fp_line
			(start 2.3749 1.970024)
			(end 2.3749 -1.970024)
			(stroke
				(width 0.1)
				(type default)
			)
			(layer "F.Fab")
		)
		(fp_line
			(start 2.3749 -1.970024)
			(end -2.3749 -1.970024)
			(stroke
				(width 0.1)
				(type default)
			)
			(layer "F.Fab")
		)
		(fp_line
			(start -2.3749 1.970024)
			(end 2.3749 1.970024)
			(stroke
				(width 0.1)
				(type default)
			)
			(layer "F.Fab")
		)
		(fp_line
			(start -2.3749 -1.970024)
			(end -2.3749 1.970024)
			(stroke
				(width 0.1)
				(type default)
			)
			(layer "F.Fab")
		)
		(fp_text user "-"
			(at 4.1656 -0.23495 180)
			(unlocked yes)
			(layer "F.Fab")
			(effects
				(font
					(size 1.905 1.4224)
					(thickness 0.1524)
				)
				(justify left)
			)
		)
		(fp_text user "+"
			(at -4.9784 -0.23495 180)
			(unlocked yes)
			(layer "F.Fab")
			(effects
				(font
					(size 1.905 1.4224)
					(thickness 0.1524)
				)
				(justify left)
			)
		)
		(pad "A" smd rect
			(at -2.450084 0 180)
			(size 2.159 2.2606)
			(layers "F.Cu" "F.Mask" "F.Paste")
			(net "GND")
		)
		(pad "C" smd rect
			(at 2.450084 0 180)
			(size 2.159 2.2606)
			(layers "F.Cu" "F.Mask" "F.Paste")
			(net "P12V_AUX")
		)
	)
	(footprint ""
		(layer "F.Cu")
		(at 426.543724 -47.92091)
		(property "Reference" "R658"
			(at 0 0 0)
			(layer "F.SilkS")
			(hide yes)
			(effects
				(font
					(size 1.27 1.27)
				)
			)
		)
		(property "Value" ""
			(at 0 0 0)
			(layer "F.Fab")
			(effects
				(font
					(size 1.27 1.27)
				)
			)
		)
		(duplicate_pad_numbers_are_jumpers no)
		(fp_line
			(start -0.7874 -0.4064)
			(end 0.7874 -0.4064)
			(stroke
				(width 0.1524)
				(type default)
			)
			(layer "F.SilkS")
		)
		(fp_line
			(start -0.7874 0.4064)
			(end -0.7874 -0.4064)
			(stroke
				(width 0.1524)
				(type default)
			)
			(layer "F.SilkS")
		)
		(fp_line
			(start 0.7874 -0.4064)
			(end 0.7874 0.4064)
			(stroke
				(width 0.1524)
				(type default)
			)
			(layer "F.SilkS")
		)
		(fp_line
			(start 0.7874 0.4064)
			(end -0.7874 0.4064)
			(stroke
				(width 0.1524)
				(type default)
			)
			(layer "F.SilkS")
		)
		(fp_line
			(start -0.67945 -0.305054)
			(end -0.12065 -0.305054)
			(stroke
				(width 0.1)
				(type default)
			)
			(layer "F.Fab")
		)
		(fp_line
			(start -0.67945 0.3048)
			(end -0.67945 -0.305054)
			(stroke
				(width 0.1)
				(type default)
			)
			(layer "F.Fab")
		)
		(fp_line
			(start -0.12065 -0.305054)
			(end -0.12065 -0.2794)
			(stroke
				(width 0.1)
				(type default)
			)
			(layer "F.Fab")
		)
		(fp_line
			(start -0.12065 -0.2794)
			(end 0.12065 -0.2794)
			(stroke
				(width 0.1)
				(type default)
			)
			(layer "F.Fab")
		)
		(fp_line
			(start -0.12065 0.2794)
			(end -0.12065 0.3048)
			(stroke
				(width 0.1)
				(type default)
			)
			(layer "F.Fab")
		)
		(fp_line
			(start -0.12065 0.3048)
			(end -0.67945 0.3048)
			(stroke
				(width 0.1)
				(type default)
			)
			(layer "F.Fab")
		)
		(fp_line
			(start 0.120396 0.2794)
			(end -0.12065 0.2794)
			(stroke
				(width 0.1)
				(type default)
			)
			(layer "F.Fab")
		)
		(fp_line
			(start 0.120396 0.3048)
			(end 0.120396 0.2794)
			(stroke
				(width 0.1)
				(type default)
			)
			(layer "F.Fab")
		)
		(fp_line
			(start 0.12065 -0.3048)
			(end 0.67945 -0.3048)
			(stroke
				(width 0.1)
				(type default)
			)
			(layer "F.Fab")
		)
		(fp_line
			(start 0.12065 -0.2794)
			(end 0.12065 -0.3048)
			(stroke
				(width 0.1)
				(type default)
			)
			(layer "F.Fab")
		)
		(fp_line
			(start 0.67945 -0.3048)
			(end 0.67945 0.3048)
			(stroke
				(width 0.1)
				(type default)
			)
			(layer "F.Fab")
		)
		(fp_line
			(start 0.67945 0.3048)
			(end 0.120396 0.3048)
			(stroke
				(width 0.1)
				(type default)
			)
			(layer "F.Fab")
		)
		(pad "1" smd circle
			(at -0.40005 0)
			(size 0 0)
			(layers "F.Cu" "F.Mask" "F.Paste")
			(net "P3V3_AUX")
		)
		(pad "2" smd circle
			(at 0.40005 0)
			(size 0 0)
			(layers "F.Cu" "F.Mask" "F.Paste")
			(net "SSD_8_15_ADC_ALERT_N")
		)
	)
	(footprint ""
		(layer "F.Cu")
		(at 372.782084 -37.025072)
		(property "Reference" "R5697"
			(at 0 0 0)
			(layer "F.SilkS")
			(hide yes)
			(effects
				(font
					(size 1.27 1.27)
				)
			)
		)
		(property "Value" ""
			(at 0 0 0)
			(layer "F.Fab")
			(effects
				(font
					(size 1.27 1.27)
				)
			)
		)
		(duplicate_pad_numbers_are_jumpers no)
		(fp_line
			(start -0.7874 -0.4064)
			(end 0.7874 -0.4064)
			(stroke
				(width 0.1524)
				(type default)
			)
			(layer "F.SilkS")
		)
		(fp_line
			(start -0.7874 0.4064)
			(end -0.7874 -0.4064)
			(stroke
				(width 0.1524)
				(type default)
			)
			(layer "F.SilkS")
		)
		(fp_line
			(start 0.7874 -0.4064)
			(end 0.7874 0.4064)
			(stroke
				(width 0.1524)
				(type default)
			)
			(layer "F.SilkS")
		)
		(fp_line
			(start 0.7874 0.4064)
			(end -0.7874 0.4064)
			(stroke
				(width 0.1524)
				(type default)
			)
			(layer "F.SilkS")
		)
		(fp_line
			(start -0.67945 -0.305054)
			(end -0.12065 -0.305054)
			(stroke
				(width 0.1)
				(type default)
			)
			(layer "F.Fab")
		)
		(fp_line
			(start -0.67945 0.3048)
			(end -0.67945 -0.305054)
			(stroke
				(width 0.1)
				(type default)
			)
			(layer "F.Fab")
		)
		(fp_line
			(start -0.12065 -0.305054)
			(end -0.12065 -0.2794)
			(stroke
				(width 0.1)
				(type default)
			)
			(layer "F.Fab")
		)
		(fp_line
			(start -0.12065 -0.2794)
			(end 0.12065 -0.2794)
			(stroke
				(width 0.1)
				(type default)
			)
			(layer "F.Fab")
		)
		(fp_line
			(start -0.12065 0.2794)
			(end -0.12065 0.3048)
			(stroke
				(width 0.1)
				(type default)
			)
			(layer "F.Fab")
		)
		(fp_line
			(start -0.12065 0.3048)
			(end -0.67945 0.3048)
			(stroke
				(width 0.1)
				(type default)
			)
			(layer "F.Fab")
		)
		(fp_line
			(start 0.120396 0.2794)
			(end -0.12065 0.2794)
			(stroke
				(width 0.1)
				(type default)
			)
			(layer "F.Fab")
		)
		(fp_line
			(start 0.120396 0.3048)
			(end 0.120396 0.2794)
			(stroke
				(width 0.1)
				(type default)
			)
			(layer "F.Fab")
		)
		(fp_line
			(start 0.12065 -0.3048)
			(end 0.67945 -0.3048)
			(stroke
				(width 0.1)
				(type default)
			)
			(layer "F.Fab")
		)
		(fp_line
			(start 0.12065 -0.2794)
			(end 0.12065 -0.3048)
			(stroke
				(width 0.1)
				(type default)
			)
			(layer "F.Fab")
		)
		(fp_line
			(start 0.67945 -0.3048)
			(end 0.67945 0.3048)
			(stroke
				(width 0.1)
				(type default)
			)
			(layer "F.Fab")
		)
		(fp_line
			(start 0.67945 0.3048)
			(end 0.120396 0.3048)
			(stroke
				(width 0.1)
				(type default)
			)
			(layer "F.Fab")
		)
		(pad "1" smd circle
			(at -0.40005 0)
			(size 0 0)
			(layers "F.Cu" "F.Mask" "F.Paste")
			(net "RST_SMB_SSD_R_N")
		)
		(pad "2" smd circle
			(at 0.40005 0)
			(size 0 0)
			(layers "F.Cu" "F.Mask" "F.Paste")
			(net "RST_SMB_SSD13_N")
		)
	)
	(footprint ""
		(layer "F.Cu")
		(at 239.14989 -209.564478 -90)
		(property "Reference" "C193"
			(at 0 0 270)
			(layer "F.SilkS")
			(hide yes)
			(effects
				(font
					(size 1.27 1.27)
				)
			)
		)
		(property "Value" ""
			(at 0 0 270)
			(layer "F.Fab")
			(effects
				(font
					(size 1.27 1.27)
				)
			)
		)
		(duplicate_pad_numbers_are_jumpers no)
		(fp_line
			(start -0.7874 0.4064)
			(end -0.7874 -0.4064)
			(stroke
				(width 0.1524)
				(type default)
			)
			(layer "F.SilkS")
		)
		(fp_line
			(start 0.7874 0.4064)
			(end -0.7874 0.4064)
			(stroke
				(width 0.1524)
				(type default)
			)
			(layer "F.SilkS")
		)
		(fp_line
			(start -0.7874 -0.4064)
			(end 0.7874 -0.4064)
			(stroke
				(width 0.1524)
				(type default)
			)
			(layer "F.SilkS")
		)
		(fp_line
			(start 0.7874 -0.4064)
			(end 0.7874 0.4064)
			(stroke
				(width 0.1524)
				(type default)
			)
			(layer "F.SilkS")
		)
		(fp_line
			(start -0.67945 0.3048)
			(end -0.67945 -0.305054)
			(stroke
				(width 0.1)
				(type default)
			)
			(layer "F.Fab")
		)
		(fp_line
			(start -0.12065 0.3048)
			(end -0.67945 0.3048)
			(stroke
				(width 0.1)
				(type default)
			)
			(layer "F.Fab")
		)
		(fp_line
			(start 0.120396 0.3048)
			(end 0.120396 0.2794)
			(stroke
				(width 0.1)
				(type default)
			)
			(layer "F.Fab")
		)
		(fp_line
			(start 0.67945 0.3048)
			(end 0.120396 0.3048)
			(stroke
				(width 0.1)
				(type default)
			)
			(layer "F.Fab")
		)
		(fp_line
			(start -0.12065 0.2794)
			(end -0.12065 0.3048)
			(stroke
				(width 0.1)
				(type default)
			)
			(layer "F.Fab")
		)
		(fp_line
			(start 0.120396 0.2794)
			(end -0.12065 0.2794)
			(stroke
				(width 0.1)
				(type default)
			)
			(layer "F.Fab")
		)
		(fp_line
			(start -0.12065 -0.2794)
			(end 0.12065 -0.2794)
			(stroke
				(width 0.1)
				(type default)
			)
			(layer "F.Fab")
		)
		(fp_line
			(start 0.12065 -0.2794)
			(end 0.12065 -0.3048)
			(stroke
				(width 0.1)
				(type default)
			)
			(layer "F.Fab")
		)
		(fp_line
			(start 0.12065 -0.3048)
			(end 0.67945 -0.3048)
			(stroke
				(width 0.1)
				(type default)
			)
			(layer "F.Fab")
		)
		(fp_line
			(start 0.67945 -0.3048)
			(end 0.67945 0.3048)
			(stroke
				(width 0.1)
				(type default)
			)
			(layer "F.Fab")
		)
		(fp_line
			(start -0.67945 -0.305054)
			(end -0.12065 -0.305054)
			(stroke
				(width 0.1)
				(type default)
			)
			(layer "F.Fab")
		)
		(fp_line
			(start -0.12065 -0.305054)
			(end -0.12065 -0.2794)
			(stroke
				(width 0.1)
				(type default)
			)
			(layer "F.Fab")
		)
		(pad "1" smd circle
			(at -0.40005 0 270)
			(size 0 0)
			(layers "F.Cu" "F.Mask" "F.Paste")
			(net "P5V_AUX_SCALED")
		)
		(pad "2" smd circle
			(at 0.40005 0 270)
			(size 0 0)
			(layers "F.Cu" "F.Mask" "F.Paste")
			(net "GND")
		)
	)
	(footprint ""
		(layer "F.Cu")
		(at 204.752194 -113.876836)
		(property "Reference" "R5955"
			(at 0 0 0)
			(layer "F.SilkS")
			(hide yes)
			(effects
				(font
					(size 1.27 1.27)
				)
			)
		)
		(property "Value" ""
			(at 0 0 0)
			(layer "F.Fab")
			(effects
				(font
					(size 1.27 1.27)
				)
			)
		)
		(duplicate_pad_numbers_are_jumpers no)
		(fp_line
			(start -0.7874 -0.4064)
			(end 0.7874 -0.4064)
			(stroke
				(width 0.1524)
				(type default)
			)
			(layer "F.SilkS")
		)
		(fp_line
			(start -0.7874 0.4064)
			(end -0.7874 -0.4064)
			(stroke
				(width 0.1524)
				(type default)
			)
			(layer "F.SilkS")
		)
		(fp_line
			(start 0.7874 -0.4064)
			(end 0.7874 0.4064)
			(stroke
				(width 0.1524)
				(type default)
			)
			(layer "F.SilkS")
		)
		(fp_line
			(start 0.7874 0.4064)
			(end -0.7874 0.4064)
			(stroke
				(width 0.1524)
				(type default)
			)
			(layer "F.SilkS")
		)
		(fp_line
			(start -0.67945 -0.305054)
			(end -0.12065 -0.305054)
			(stroke
				(width 0.1)
				(type default)
			)
			(layer "F.Fab")
		)
		(fp_line
			(start -0.67945 0.3048)
			(end -0.67945 -0.305054)
			(stroke
				(width 0.1)
				(type default)
			)
			(layer "F.Fab")
		)
		(fp_line
			(start -0.12065 -0.305054)
			(end -0.12065 -0.2794)
			(stroke
				(width 0.1)
				(type default)
			)
			(layer "F.Fab")
		)
		(fp_line
			(start -0.12065 -0.2794)
			(end 0.12065 -0.2794)
			(stroke
				(width 0.1)
				(type default)
			)
			(layer "F.Fab")
		)
		(fp_line
			(start -0.12065 0.2794)
			(end -0.12065 0.3048)
			(stroke
				(width 0.1)
				(type default)
			)
			(layer "F.Fab")
		)
		(fp_line
			(start -0.12065 0.3048)
			(end -0.67945 0.3048)
			(stroke
				(width 0.1)
				(type default)
			)
			(layer "F.Fab")
		)
		(fp_line
			(start 0.120396 0.2794)
			(end -0.12065 0.2794)
			(stroke
				(width 0.1)
				(type default)
			)
			(layer "F.Fab")
		)
		(fp_line
			(start 0.120396 0.3048)
			(end 0.120396 0.2794)
			(stroke
				(width 0.1)
				(type default)
			)
			(layer "F.Fab")
		)
		(fp_line
			(start 0.12065 -0.3048)
			(end 0.67945 -0.3048)
			(stroke
				(width 0.1)
				(type default)
			)
			(layer "F.Fab")
		)
		(fp_line
			(start 0.12065 -0.2794)
			(end 0.12065 -0.3048)
			(stroke
				(width 0.1)
				(type default)
			)
			(layer "F.Fab")
		)
		(fp_line
			(start 0.67945 -0.3048)
			(end 0.67945 0.3048)
			(stroke
				(width 0.1)
				(type default)
			)
			(layer "F.Fab")
		)
		(fp_line
			(start 0.67945 0.3048)
			(end 0.120396 0.3048)
			(stroke
				(width 0.1)
				(type default)
			)
			(layer "F.Fab")
		)
		(pad "1" smd circle
			(at -0.40005 0)
			(size 0 0)
			(layers "F.Cu" "F.Mask" "F.Paste")
			(net "HP_NIC3_EN")
		)
		(pad "2" smd circle
			(at 0.40005 0)
			(size 0 0)
			(layers "F.Cu" "F.Mask" "F.Paste")
			(net "P3V3_NIC3_CO_EN")
		)
	)
	(footprint ""
		(layer "F.Cu")
		(at 378.852684 -81.9658)
		(property "Reference" "R1777"
			(at 0 0 0)
			(layer "F.SilkS")
			(hide yes)
			(effects
				(font
					(size 1.27 1.27)
				)
			)
		)
		(property "Value" ""
			(at 0 0 0)
			(layer "F.Fab")
			(effects
				(font
					(size 1.27 1.27)
				)
			)
		)
		(duplicate_pad_numbers_are_jumpers no)
		(fp_line
			(start -0.7874 -0.4064)
			(end 0.7874 -0.4064)
			(stroke
				(width 0.1524)
				(type default)
			)
			(layer "F.SilkS")
		)
		(fp_line
			(start -0.7874 0.4064)
			(end -0.7874 -0.4064)
			(stroke
				(width 0.1524)
				(type default)
			)
			(layer "F.SilkS")
		)
		(fp_line
			(start 0.7874 -0.4064)
			(end 0.7874 0.4064)
			(stroke
				(width 0.1524)
				(type default)
			)
			(layer "F.SilkS")
		)
		(fp_line
			(start 0.7874 0.4064)
			(end -0.7874 0.4064)
			(stroke
				(width 0.1524)
				(type default)
			)
			(layer "F.SilkS")
		)
		(fp_line
			(start -0.67945 -0.305054)
			(end -0.12065 -0.305054)
			(stroke
				(width 0.1)
				(type default)
			)
			(layer "F.Fab")
		)
		(fp_line
			(start -0.67945 0.3048)
			(end -0.67945 -0.305054)
			(stroke
				(width 0.1)
				(type default)
			)
			(layer "F.Fab")
		)
		(fp_line
			(start -0.12065 -0.305054)
			(end -0.12065 -0.2794)
			(stroke
				(width 0.1)
				(type default)
			)
			(layer "F.Fab")
		)
		(fp_line
			(start -0.12065 -0.2794)
			(end 0.12065 -0.2794)
			(stroke
				(width 0.1)
				(type default)
			)
			(layer "F.Fab")
		)
		(fp_line
			(start -0.12065 0.2794)
			(end -0.12065 0.3048)
			(stroke
				(width 0.1)
				(type default)
			)
			(layer "F.Fab")
		)
		(fp_line
			(start -0.12065 0.3048)
			(end -0.67945 0.3048)
			(stroke
				(width 0.1)
				(type default)
			)
			(layer "F.Fab")
		)
		(fp_line
			(start 0.120396 0.2794)
			(end -0.12065 0.2794)
			(stroke
				(width 0.1)
				(type default)
			)
			(layer "F.Fab")
		)
		(fp_line
			(start 0.120396 0.3048)
			(end 0.120396 0.2794)
			(stroke
				(width 0.1)
				(type default)
			)
			(layer "F.Fab")
		)
		(fp_line
			(start 0.12065 -0.3048)
			(end 0.67945 -0.3048)
			(stroke
				(width 0.1)
				(type default)
			)
			(layer "F.Fab")
		)
		(fp_line
			(start 0.12065 -0.2794)
			(end 0.12065 -0.3048)
			(stroke
				(width 0.1)
				(type default)
			)
			(layer "F.Fab")
		)
		(fp_line
			(start 0.67945 -0.3048)
			(end 0.67945 0.3048)
			(stroke
				(width 0.1)
				(type default)
			)
			(layer "F.Fab")
		)
		(fp_line
			(start 0.67945 0.3048)
			(end 0.120396 0.3048)
			(stroke
				(width 0.1)
				(type default)
			)
			(layer "F.Fab")
		)
		(pad "1" smd circle
			(at -0.40005 0)
			(size 0 0)
			(layers "F.Cu" "F.Mask" "F.Paste")
			(net "SMB_BIC_I2C6_MUX_SSD_0_7_ADC_R_SDA")
		)
		(pad "2" smd circle
			(at 0.40005 0)
			(size 0 0)
			(layers "F.Cu" "F.Mask" "F.Paste")
			(net "SMB_BIC_I2C6_MUX_SSD_0_7_ADC_SDA")
		)
	)
)
